G04*
G04 #@! TF.GenerationSoftware,Altium Limited,Altium Designer,23.6.0 (18)*
G04*
G04 Layer_Physical_Order=2*
G04 Layer_Color=36540*
%FSLAX44Y44*%
%MOMM*%
G71*
G04*
G04 #@! TF.SameCoordinates,0D6CC9A4-690D-4EF8-AA6E-9FB67146BD04*
G04*
G04*
G04 #@! TF.FilePolarity,Positive*
G04*
G01*
G75*
%ADD76R,2.0200X2.0200*%
%ADD77C,2.0200*%
%ADD78C,2.0900*%
%ADD79C,5.3000*%
%ADD80C,0.6000*%
G36*
X503922Y502958D02*
X503922Y5000D01*
X503921Y4999D01*
X503290Y4368D01*
X502957Y4078D01*
X5000Y4078D01*
X4919D01*
X4078Y5042D01*
X4078Y502953D01*
X4746Y503699D01*
X5000Y503921D01*
X503000Y503922D01*
X503081D01*
X503922Y502958D01*
D02*
G37*
%LPC*%
G36*
X193522Y499450D02*
X190478D01*
X187493Y498856D01*
X184682Y497692D01*
X182151Y496001D01*
X179999Y493849D01*
X178308Y491318D01*
X177687Y489819D01*
X176313D01*
X175692Y491318D01*
X174001Y493849D01*
X171849Y496001D01*
X169318Y497692D01*
X166507Y498856D01*
X163522Y499450D01*
X160478D01*
X157493Y498856D01*
X154682Y497692D01*
X152151Y496001D01*
X149999Y493849D01*
X148308Y491318D01*
X147144Y488507D01*
X146550Y485522D01*
Y482478D01*
X147144Y479493D01*
X148308Y476682D01*
X149999Y474151D01*
X152151Y471999D01*
X154682Y470308D01*
X157493Y469144D01*
X160478Y468550D01*
X163522D01*
X166507Y469144D01*
X169318Y470308D01*
X171849Y471999D01*
X174001Y474151D01*
X175692Y476682D01*
X176313Y478181D01*
X177687D01*
X178308Y476682D01*
X179999Y474151D01*
X182151Y471999D01*
X184682Y470308D01*
X187493Y469144D01*
X190478Y468550D01*
X193522D01*
X196507Y469144D01*
X199318Y470308D01*
X201849Y471999D01*
X204001Y474151D01*
X205692Y476682D01*
X206856Y479493D01*
X207450Y482478D01*
Y485522D01*
X206856Y488507D01*
X205692Y491318D01*
X204001Y493849D01*
X201849Y496001D01*
X199318Y497692D01*
X196507Y498856D01*
X193522Y499450D01*
D02*
G37*
G36*
X242495Y483750D02*
X240505D01*
X238668Y482989D01*
X237261Y481582D01*
X236500Y479745D01*
Y477755D01*
X237261Y475918D01*
X238668Y474511D01*
X240505Y473750D01*
X242495D01*
X244332Y474511D01*
X245739Y475918D01*
X246500Y477755D01*
Y479745D01*
X245739Y481582D01*
X244332Y482989D01*
X242495Y483750D01*
D02*
G37*
G36*
X133639Y496450D02*
X130361D01*
X127194Y495602D01*
X124355Y493963D01*
X122037Y491645D01*
X120398Y488806D01*
X119550Y485639D01*
Y482361D01*
X120398Y479194D01*
X122037Y476356D01*
X124355Y474038D01*
X127194Y472398D01*
X130361Y471550D01*
X133639D01*
X136805Y472398D01*
X139644Y474038D01*
X141962Y476356D01*
X143602Y479194D01*
X144450Y482361D01*
Y485639D01*
X143602Y488806D01*
X141962Y491645D01*
X139644Y493963D01*
X136805Y495602D01*
X133639Y496450D01*
D02*
G37*
G36*
X103639D02*
X100361D01*
X97194Y495602D01*
X94355Y493963D01*
X92037Y491645D01*
X90398Y488806D01*
X89550Y485639D01*
Y482361D01*
X90398Y479194D01*
X92037Y476356D01*
X94355Y474038D01*
X97194Y472398D01*
X100361Y471550D01*
X103639D01*
X106805Y472398D01*
X109644Y474038D01*
X111962Y476356D01*
X113602Y479194D01*
X114450Y482361D01*
Y485639D01*
X113602Y488806D01*
X111962Y491645D01*
X109644Y493963D01*
X106805Y495602D01*
X103639Y496450D01*
D02*
G37*
G36*
X73639D02*
X70361D01*
X67194Y495602D01*
X64356Y493963D01*
X62038Y491645D01*
X60399Y488806D01*
X59550Y485639D01*
Y482361D01*
X60399Y479194D01*
X62038Y476356D01*
X64356Y474038D01*
X67194Y472398D01*
X70361Y471550D01*
X73639D01*
X76806Y472398D01*
X79644Y474038D01*
X81962Y476356D01*
X83602Y479194D01*
X84450Y482361D01*
Y485639D01*
X83602Y488806D01*
X81962Y491645D01*
X79644Y493963D01*
X76806Y495602D01*
X73639Y496450D01*
D02*
G37*
G36*
X49000Y469912D02*
X45986Y469105D01*
X43024Y467395D01*
X40605Y464976D01*
X38895Y462014D01*
X38088Y459000D01*
X49000D01*
Y469912D01*
D02*
G37*
G36*
X140744Y468508D02*
X138755D01*
X136918Y467747D01*
X135511Y466340D01*
X134750Y464503D01*
Y462514D01*
X135511Y460676D01*
X136918Y459269D01*
X138755Y458508D01*
X140744D01*
X142582Y459269D01*
X143989Y460676D01*
X144750Y462514D01*
Y464503D01*
X143989Y466340D01*
X142582Y467747D01*
X140744Y468508D01*
D02*
G37*
G36*
X53000Y469912D02*
Y459000D01*
X63912D01*
X63863Y459186D01*
X64017Y459366D01*
X65749Y459430D01*
X66168Y459011D01*
X68005Y458250D01*
X69995D01*
X71832Y459011D01*
X73239Y460418D01*
X74000Y462255D01*
Y464245D01*
X73239Y466082D01*
X71832Y467489D01*
X69995Y468250D01*
X68005D01*
X66168Y467489D01*
X64761Y466082D01*
X64000Y464245D01*
Y463003D01*
X62730Y462663D01*
X61395Y464976D01*
X58976Y467395D01*
X56014Y469105D01*
X53000Y469912D01*
D02*
G37*
G36*
X49000Y455000D02*
X38088D01*
X38895Y451986D01*
X40605Y449024D01*
X43024Y446605D01*
X45986Y444895D01*
X49000Y444088D01*
Y455000D01*
D02*
G37*
G36*
X63912D02*
X53000D01*
Y444088D01*
X56014Y444895D01*
X58976Y446605D01*
X61395Y449024D01*
X63105Y451986D01*
X63912Y455000D01*
D02*
G37*
G36*
X458522Y472450D02*
X455478D01*
X452493Y471856D01*
X449682Y470692D01*
X447151Y469001D01*
X444999Y466849D01*
X443308Y464318D01*
X442144Y461507D01*
X441550Y458522D01*
Y455478D01*
X442144Y452493D01*
X443308Y449682D01*
X444999Y447151D01*
X447151Y444999D01*
X449682Y443308D01*
X452493Y442144D01*
X455478Y441550D01*
X458522D01*
X461507Y442144D01*
X464318Y443308D01*
X466849Y444999D01*
X469001Y447151D01*
X470692Y449682D01*
X471856Y452493D01*
X472450Y455478D01*
Y458522D01*
X471856Y461507D01*
X470692Y464318D01*
X469001Y466849D01*
X466849Y469001D01*
X464318Y470692D01*
X461507Y471856D01*
X458522Y472450D01*
D02*
G37*
G36*
X415019Y472500D02*
X410981D01*
X407020Y471712D01*
X403290Y470167D01*
X399932Y467923D01*
X397077Y465068D01*
X394833Y461710D01*
X393288Y457980D01*
X392500Y454019D01*
Y449981D01*
X393288Y446020D01*
X394833Y442290D01*
X397077Y438932D01*
X399932Y436077D01*
X403290Y433833D01*
X407020Y432288D01*
X410981Y431500D01*
X415019D01*
X418980Y432288D01*
X422710Y433833D01*
X426068Y436077D01*
X428923Y438932D01*
X431167Y442290D01*
X432712Y446020D01*
X433500Y449981D01*
Y454019D01*
X432712Y457980D01*
X431167Y461710D01*
X428923Y465068D01*
X426068Y467923D01*
X422710Y470167D01*
X418980Y471712D01*
X415019Y472500D01*
D02*
G37*
G36*
X235392Y427690D02*
X233403D01*
X231566Y426929D01*
X230159Y425522D01*
X229398Y423685D01*
Y421696D01*
X230159Y419858D01*
X231566Y418451D01*
X233403Y417690D01*
X235392D01*
X237230Y418451D01*
X238637Y419858D01*
X239398Y421696D01*
Y423685D01*
X238637Y425522D01*
X237230Y426929D01*
X235392Y427690D01*
D02*
G37*
G36*
X97019Y457500D02*
X92981D01*
X89020Y456712D01*
X85289Y455167D01*
X81932Y452923D01*
X79077Y450068D01*
X76833Y446710D01*
X75288Y442980D01*
X74500Y439019D01*
Y434981D01*
X75288Y431020D01*
X76833Y427290D01*
X79077Y423932D01*
X81932Y421077D01*
X85289Y418833D01*
X89020Y417288D01*
X92981Y416500D01*
X97019D01*
X100980Y417288D01*
X104710Y418833D01*
X108068Y421077D01*
X110923Y423932D01*
X113167Y427290D01*
X114712Y431020D01*
X115500Y434981D01*
Y439019D01*
X114712Y442980D01*
X113167Y446710D01*
X110923Y450068D01*
X108068Y452923D01*
X104710Y455167D01*
X100980Y456712D01*
X97019Y457500D01*
D02*
G37*
G36*
X224367Y420288D02*
X222378D01*
X220540Y419527D01*
X219134Y418120D01*
X218373Y416283D01*
Y414294D01*
X219134Y412456D01*
X220540Y411049D01*
X222378Y410288D01*
X224367D01*
X226205Y411049D01*
X227611Y412456D01*
X228373Y414294D01*
Y416283D01*
X227611Y418120D01*
X226205Y419527D01*
X224367Y420288D01*
D02*
G37*
G36*
X18780Y402960D02*
X16791D01*
X14953Y402199D01*
X13547Y400792D01*
X12785Y398955D01*
Y396965D01*
X13547Y395128D01*
X14953Y393721D01*
X16791Y392960D01*
X18780D01*
X20618Y393721D01*
X22024Y395128D01*
X22785Y396965D01*
Y398955D01*
X22024Y400792D01*
X20618Y402199D01*
X18780Y402960D01*
D02*
G37*
G36*
X346264Y398919D02*
X344275D01*
X342437Y398158D01*
X341031Y396751D01*
X340269Y394914D01*
Y392924D01*
X341031Y391087D01*
X342437Y389680D01*
X344275Y388919D01*
X346264D01*
X348102Y389680D01*
X349508Y391087D01*
X350269Y392924D01*
Y394914D01*
X349508Y396751D01*
X348102Y398158D01*
X346264Y398919D01*
D02*
G37*
G36*
X316245Y397363D02*
X314256D01*
X312418Y396602D01*
X311011Y395196D01*
X310250Y393358D01*
Y391369D01*
X311011Y389531D01*
X312418Y388124D01*
X314256Y387363D01*
X316245D01*
X318082Y388124D01*
X319489Y389531D01*
X320250Y391369D01*
Y393358D01*
X319489Y395196D01*
X318082Y396602D01*
X316245Y397363D01*
D02*
G37*
G36*
X392022Y366264D02*
X390033D01*
X388195Y365503D01*
X386789Y364096D01*
X386028Y362258D01*
Y360269D01*
X386789Y358432D01*
X388195Y357025D01*
X390033Y356264D01*
X392022D01*
X393860Y357025D01*
X395266Y358432D01*
X396028Y360269D01*
Y362258D01*
X395266Y364096D01*
X393860Y365503D01*
X392022Y366264D01*
D02*
G37*
G36*
X18495Y372710D02*
X16505D01*
X14668Y371949D01*
X13261Y370542D01*
X12500Y368704D01*
Y366715D01*
X13261Y364878D01*
X14668Y363471D01*
X15148Y363272D01*
Y361898D01*
X14668Y361699D01*
X13261Y360292D01*
X12500Y358455D01*
Y356465D01*
X13261Y354628D01*
X14668Y353221D01*
X16505Y352460D01*
X18495D01*
X20332Y353221D01*
X21739Y354628D01*
X22500Y356465D01*
Y358455D01*
X21739Y360292D01*
X20332Y361699D01*
X19852Y361898D01*
Y363272D01*
X20332Y363471D01*
X21739Y364878D01*
X22500Y366715D01*
Y368704D01*
X21739Y370542D01*
X20332Y371949D01*
X18495Y372710D01*
D02*
G37*
G36*
X96604Y358378D02*
X94615D01*
X92777Y357617D01*
X91371Y356210D01*
X90610Y354372D01*
Y352383D01*
X91371Y350546D01*
X92777Y349139D01*
X94615Y348378D01*
X96604D01*
X98442Y349139D01*
X99848Y350546D01*
X100610Y352383D01*
Y354372D01*
X99848Y356210D01*
X98442Y357617D01*
X96604Y358378D01*
D02*
G37*
G36*
X355745Y344500D02*
X353755D01*
X351918Y343739D01*
X350511Y342332D01*
X349750Y340495D01*
Y338505D01*
X350511Y336668D01*
X351918Y335261D01*
X353755Y334500D01*
X355745D01*
X357582Y335261D01*
X358989Y336668D01*
X359750Y338505D01*
Y340495D01*
X358989Y342332D01*
X357582Y343739D01*
X355745Y344500D01*
D02*
G37*
G36*
X221963Y344000D02*
X219974D01*
X218136Y343239D01*
X216730Y341832D01*
X215968Y339995D01*
Y338005D01*
X216730Y336168D01*
X218136Y334761D01*
X219974Y334000D01*
X221963D01*
X223801Y334761D01*
X225207Y336168D01*
X225968Y338005D01*
Y339995D01*
X225207Y341832D01*
X223801Y343239D01*
X221963Y344000D01*
D02*
G37*
G36*
X467243Y377500D02*
X462757D01*
X458326Y376798D01*
X454060Y375412D01*
X450063Y373375D01*
X446433Y370739D01*
X443261Y367566D01*
X440625Y363937D01*
X438588Y359940D01*
X437202Y355674D01*
X436500Y351243D01*
Y346757D01*
X437202Y342326D01*
X438588Y338060D01*
X440625Y334063D01*
X443261Y330434D01*
X446433Y327261D01*
X450063Y324625D01*
X454060Y322588D01*
X458326Y321202D01*
X462757Y320500D01*
X467243D01*
X471674Y321202D01*
X475940Y322588D01*
X479937Y324625D01*
X483567Y327261D01*
X486739Y330434D01*
X489375Y334063D01*
X491412Y338060D01*
X492798Y342326D01*
X493500Y346757D01*
Y351243D01*
X492798Y355674D01*
X491412Y359940D01*
X489375Y363937D01*
X486739Y367566D01*
X483567Y370739D01*
X479937Y373375D01*
X475940Y375412D01*
X471674Y376798D01*
X467243Y377500D01*
D02*
G37*
G36*
X245239Y297311D02*
X243250D01*
X241412Y296550D01*
X240006Y295143D01*
X239245Y293305D01*
Y291316D01*
X240006Y289479D01*
X241412Y288072D01*
X243250Y287311D01*
X245239D01*
X247077Y288072D01*
X248483Y289479D01*
X249245Y291316D01*
Y293305D01*
X248483Y295143D01*
X247077Y296550D01*
X245239Y297311D01*
D02*
G37*
G36*
X404053Y282430D02*
X401947D01*
X399912Y281885D01*
X398088Y280832D01*
X396599Y279343D01*
X395545Y277518D01*
X395000Y275484D01*
Y273377D01*
X395545Y271343D01*
X396599Y269518D01*
X398088Y268029D01*
X399912Y266976D01*
X401947Y266430D01*
X404053D01*
X406088Y266976D01*
X407912Y268029D01*
X409402Y269518D01*
X410455Y271343D01*
X411000Y273377D01*
Y275484D01*
X410455Y277518D01*
X409402Y279343D01*
X407912Y280832D01*
X406088Y281885D01*
X404053Y282430D01*
D02*
G37*
G36*
X459000Y266912D02*
Y256000D01*
X469912D01*
X469105Y259014D01*
X467395Y261976D01*
X464976Y264395D01*
X462014Y266105D01*
X459000Y266912D01*
D02*
G37*
G36*
X455000Y266912D02*
X451986Y266105D01*
X449024Y264395D01*
X446605Y261976D01*
X444895Y259014D01*
X444088Y256000D01*
X455000D01*
Y266912D01*
D02*
G37*
G36*
X244495Y262561D02*
X242505D01*
X240668Y261800D01*
X239261Y260393D01*
X238500Y258556D01*
Y256566D01*
X239261Y254729D01*
X240668Y253322D01*
X242505Y252561D01*
X244495D01*
X246332Y253322D01*
X247739Y254729D01*
X248500Y256566D01*
Y258556D01*
X247739Y260393D01*
X246332Y261800D01*
X244495Y262561D01*
D02*
G37*
G36*
X469912Y252000D02*
X459000D01*
Y241088D01*
X462014Y241895D01*
X464976Y243605D01*
X467395Y246024D01*
X469105Y248986D01*
X469912Y252000D01*
D02*
G37*
G36*
X455000D02*
X444088D01*
X444895Y248986D01*
X446605Y246024D01*
X449024Y243605D01*
X451986Y241895D01*
X455000Y241088D01*
Y252000D01*
D02*
G37*
G36*
X259933Y214744D02*
X257944D01*
X256106Y213983D01*
X254700Y212576D01*
X253939Y210738D01*
Y208749D01*
X254700Y206912D01*
X256106Y205505D01*
X257944Y204744D01*
X259933D01*
X261771Y205505D01*
X263178Y206912D01*
X263939Y208749D01*
Y210738D01*
X263178Y212576D01*
X261771Y213983D01*
X259933Y214744D01*
D02*
G37*
G36*
X244933D02*
X242944D01*
X241106Y213983D01*
X239700Y212576D01*
X238939Y210738D01*
Y208749D01*
X239700Y206912D01*
X241106Y205505D01*
X242944Y204744D01*
X244933D01*
X246771Y205505D01*
X248178Y206912D01*
X248939Y208749D01*
Y210738D01*
X248178Y212576D01*
X246771Y213983D01*
X244933Y214744D01*
D02*
G37*
G36*
X229418D02*
X227429D01*
X225591Y213983D01*
X224185Y212576D01*
X223424Y210738D01*
Y208749D01*
X224185Y206912D01*
X225591Y205505D01*
X227429Y204744D01*
X229418D01*
X231256Y205505D01*
X232662Y206912D01*
X233424Y208749D01*
Y210738D01*
X232662Y212576D01*
X231256Y213983D01*
X229418Y214744D01*
D02*
G37*
G36*
X315995Y208311D02*
X314006D01*
X312168Y207550D01*
X310761Y206143D01*
X310000Y204306D01*
Y202316D01*
X310761Y200479D01*
X312168Y199072D01*
X314006Y198311D01*
X315995D01*
X317832Y199072D01*
X319239Y200479D01*
X320000Y202316D01*
Y204306D01*
X319239Y206143D01*
X317832Y207550D01*
X315995Y208311D01*
D02*
G37*
G36*
X280201Y195705D02*
X278212D01*
X276374Y194944D01*
X274967Y193537D01*
X274206Y191700D01*
Y189711D01*
X274967Y187873D01*
X276374Y186466D01*
X278212Y185705D01*
X280201D01*
X282038Y186466D01*
X283445Y187873D01*
X284206Y189711D01*
Y191700D01*
X283445Y193537D01*
X282038Y194944D01*
X280201Y195705D01*
D02*
G37*
G36*
X225124Y193721D02*
X223134D01*
X221297Y192960D01*
X219890Y191553D01*
X219129Y189715D01*
Y187726D01*
X219890Y185889D01*
X221297Y184482D01*
X223134Y183721D01*
X225124D01*
X226961Y184482D01*
X228368Y185889D01*
X229129Y187726D01*
Y189715D01*
X228368Y191553D01*
X226961Y192960D01*
X225124Y193721D01*
D02*
G37*
G36*
X57650Y191550D02*
X54771Y190779D01*
X51889Y189114D01*
X49535Y186761D01*
X47871Y183879D01*
X47620Y182941D01*
X46350Y183108D01*
Y191100D01*
X22150D01*
Y166900D01*
X46350D01*
Y174892D01*
X47620Y175059D01*
X47871Y174121D01*
X49535Y171239D01*
X51889Y168885D01*
X54771Y167221D01*
X57650Y166450D01*
Y179000D01*
Y191550D01*
D02*
G37*
G36*
X61650D02*
Y181000D01*
X72200D01*
X71429Y183879D01*
X69764Y186761D01*
X67411Y189114D01*
X64529Y190779D01*
X61650Y191550D01*
D02*
G37*
G36*
X244933Y187955D02*
X242944D01*
X241106Y187194D01*
X239700Y185787D01*
X238939Y183950D01*
Y181961D01*
X239700Y180123D01*
X241106Y178716D01*
X242944Y177955D01*
X244933D01*
X246771Y178716D01*
X248178Y180123D01*
X248939Y181961D01*
Y183950D01*
X248178Y185787D01*
X246771Y187194D01*
X244933Y187955D01*
D02*
G37*
G36*
X259933Y187705D02*
X257944D01*
X256106Y186944D01*
X254700Y185537D01*
X253939Y183700D01*
Y181710D01*
X254700Y179873D01*
X256106Y178466D01*
X257944Y177705D01*
X259933D01*
X261771Y178466D01*
X263178Y179873D01*
X263939Y181710D01*
Y183700D01*
X263178Y185537D01*
X261771Y186944D01*
X259933Y187705D01*
D02*
G37*
G36*
X404053Y193091D02*
X401947D01*
X399912Y192545D01*
X398088Y191492D01*
X396599Y190003D01*
X395545Y188179D01*
X395000Y186144D01*
Y184037D01*
X395545Y182003D01*
X396599Y180179D01*
X398088Y178689D01*
X399912Y177636D01*
X401947Y177091D01*
X404053D01*
X406088Y177636D01*
X407912Y178689D01*
X409402Y180179D01*
X410455Y182003D01*
X411000Y184037D01*
Y186144D01*
X410455Y188179D01*
X409402Y190003D01*
X407912Y191492D01*
X406088Y192545D01*
X404053Y193091D01*
D02*
G37*
G36*
X212995Y179955D02*
X211005D01*
X209168Y179194D01*
X207761Y177787D01*
X207000Y175950D01*
Y173960D01*
X207761Y172123D01*
X209168Y170716D01*
X211005Y169955D01*
X212995D01*
X214832Y170716D01*
X216239Y172123D01*
X217000Y173960D01*
Y175950D01*
X216239Y177787D01*
X214832Y179194D01*
X212995Y179955D01*
D02*
G37*
G36*
X72200Y177000D02*
X61650D01*
Y166450D01*
X64529Y167221D01*
X67411Y168885D01*
X69764Y171239D01*
X71429Y174121D01*
X72200Y177000D01*
D02*
G37*
G36*
X352156Y131070D02*
X350167D01*
X348329Y130309D01*
X347171Y129150D01*
X346082Y130239D01*
X344245Y131000D01*
X342255D01*
X340418Y130239D01*
X339011Y128832D01*
X338250Y126995D01*
Y125005D01*
X339011Y123168D01*
X340418Y121761D01*
X340648Y121666D01*
Y120291D01*
X339918Y119989D01*
X338511Y118582D01*
X337750Y116745D01*
Y114755D01*
X338511Y112918D01*
X339918Y111511D01*
X340804Y111144D01*
Y109769D01*
X339738Y109328D01*
X338331Y107921D01*
X337570Y106083D01*
Y104094D01*
X338331Y102256D01*
X339738Y100850D01*
X339968Y100755D01*
Y99380D01*
X339238Y99078D01*
X337831Y97671D01*
X337070Y95833D01*
Y93844D01*
X337831Y92007D01*
X339238Y90600D01*
X340717Y89987D01*
X340844Y88669D01*
X340843Y88665D01*
X340418Y88489D01*
X339011Y87082D01*
X338250Y85245D01*
Y83255D01*
X339011Y81418D01*
X340418Y80011D01*
X340648Y79916D01*
Y78541D01*
X339918Y78239D01*
X338511Y76832D01*
X337750Y74995D01*
Y73005D01*
X338511Y71168D01*
X339918Y69761D01*
X340804Y69394D01*
Y68019D01*
X339738Y67578D01*
X338331Y66171D01*
X337570Y64333D01*
Y62344D01*
X338331Y60507D01*
X339738Y59100D01*
X339968Y59005D01*
Y57630D01*
X339238Y57328D01*
X337831Y55921D01*
X337070Y54083D01*
Y52094D01*
X337831Y50257D01*
X339238Y48850D01*
X339044Y47555D01*
X338750Y46845D01*
Y44856D01*
X339511Y43018D01*
X340918Y41611D01*
X341148Y41516D01*
Y40142D01*
X340418Y39839D01*
X339011Y38433D01*
X338250Y36595D01*
Y34606D01*
X339011Y32768D01*
X340418Y31361D01*
X342255Y30600D01*
X344245D01*
X346082Y31361D01*
X347489Y32768D01*
X348247Y34598D01*
X348917Y34320D01*
X350906D01*
X352743Y35081D01*
X354150Y36488D01*
X354245Y36718D01*
X355620D01*
X355922Y35988D01*
X357329Y34581D01*
X359167Y33820D01*
X361156D01*
X362994Y34581D01*
X364400Y35988D01*
X365161Y37826D01*
Y39815D01*
X364400Y41652D01*
X362994Y43059D01*
X361156Y43820D01*
X359167D01*
X357329Y43059D01*
X355922Y41652D01*
X355827Y41422D01*
X354452D01*
X354150Y42152D01*
X352743Y43559D01*
X350906Y44320D01*
X349903D01*
X348847Y44811D01*
X348750Y45493D01*
Y45897D01*
X349111Y46914D01*
X349923Y47070D01*
X351156D01*
X352994Y47831D01*
X354400Y49238D01*
X354495Y49468D01*
X355870D01*
X356172Y48738D01*
X357579Y47331D01*
X359417Y46570D01*
X361406D01*
X363243Y47331D01*
X364650Y48738D01*
X365411Y50575D01*
Y52565D01*
X364650Y54402D01*
X363243Y55809D01*
X361406Y56570D01*
X359417D01*
X357579Y55809D01*
X356172Y54402D01*
X356077Y54172D01*
X354702D01*
X354400Y54902D01*
X352994Y56309D01*
X351156Y57070D01*
X349167D01*
X347329Y56309D01*
X346836Y55816D01*
X346309Y55921D01*
X344902Y57328D01*
X344672Y57423D01*
Y58798D01*
X345402Y59100D01*
X346676Y60374D01*
X347775Y59275D01*
X349612Y58513D01*
X351601D01*
X353439Y59275D01*
X354846Y60681D01*
X354941Y60911D01*
X356316D01*
X356618Y60181D01*
X358025Y58775D01*
X359862Y58014D01*
X361851D01*
X363689Y58775D01*
X365096Y60181D01*
X365857Y62019D01*
Y64008D01*
X365096Y65846D01*
X363689Y67252D01*
X361851Y68014D01*
X359862D01*
X358025Y67252D01*
X356618Y65846D01*
X356523Y65616D01*
X355148D01*
X354846Y66346D01*
X353439Y67752D01*
X351601Y68513D01*
X349612D01*
X347775Y67752D01*
X346501Y66479D01*
X345402Y67578D01*
X344516Y67945D01*
Y69320D01*
X345582Y69761D01*
X346096Y70275D01*
X347329Y70831D01*
X348024Y70543D01*
X349167Y70070D01*
X351156D01*
X352994Y70831D01*
X354400Y72238D01*
X354495Y72468D01*
X355870D01*
X356172Y71738D01*
X357579Y70331D01*
X359417Y69570D01*
X361406D01*
X363243Y70331D01*
X364650Y71738D01*
X365411Y73576D01*
Y75565D01*
X364650Y77402D01*
X363243Y78809D01*
X361406Y79570D01*
X359417D01*
X357579Y78809D01*
X356172Y77402D01*
X356077Y77172D01*
X354702D01*
X354400Y77902D01*
X352994Y79309D01*
X351156Y80070D01*
X349167D01*
X347329Y79309D01*
X346816Y78796D01*
X346500Y78653D01*
X346311Y78731D01*
X346198Y79363D01*
X346216Y80145D01*
X347489Y81418D01*
X348250Y83255D01*
Y84636D01*
X349372Y85512D01*
X349423Y85524D01*
X349917Y85320D01*
X351906D01*
X353744Y86081D01*
X355150Y87488D01*
X355245Y87718D01*
X356620D01*
X356922Y86988D01*
X358329Y85581D01*
X360167Y84820D01*
X362156D01*
X363993Y85581D01*
X365400Y86988D01*
X366161Y88826D01*
Y90815D01*
X365400Y92652D01*
X363993Y94059D01*
X362156Y94820D01*
X360167D01*
X358329Y94059D01*
X356922Y92652D01*
X356827Y92422D01*
X355452D01*
X355150Y93152D01*
X353744Y94559D01*
X351906Y95320D01*
X349917D01*
X348340Y94667D01*
X347457Y95044D01*
X347070Y95346D01*
Y95833D01*
X346309Y97671D01*
X344950Y99030D01*
X344937Y99986D01*
X344951Y100346D01*
X345562Y100723D01*
X346876Y100350D01*
X346922Y100238D01*
X348329Y98831D01*
X350167Y98070D01*
X352156D01*
X353993Y98831D01*
X355400Y100238D01*
X355495Y100468D01*
X356870D01*
X357172Y99738D01*
X358579Y98331D01*
X360417Y97570D01*
X362406D01*
X364244Y98331D01*
X365650Y99738D01*
X366411Y101575D01*
Y103565D01*
X365650Y105402D01*
X364244Y106809D01*
X362406Y107570D01*
X360417D01*
X358579Y106809D01*
X357172Y105402D01*
X357077Y105172D01*
X355702D01*
X355400Y105902D01*
X353993Y107309D01*
X352156Y108070D01*
X350167D01*
X348421Y107347D01*
X348025Y107265D01*
X346996Y107469D01*
X346809Y107921D01*
X345402Y109328D01*
X344516Y109695D01*
Y111069D01*
X345582Y111511D01*
X346087Y112015D01*
X347332Y111768D01*
X347368Y111681D01*
X348775Y110275D01*
X350612Y109514D01*
X352601D01*
X354439Y110275D01*
X355846Y111681D01*
X355941Y111911D01*
X357316D01*
X357618Y111181D01*
X359025Y109775D01*
X360862Y109014D01*
X362851D01*
X364689Y109775D01*
X366096Y111181D01*
X366857Y113019D01*
Y115008D01*
X366096Y116846D01*
X364689Y118252D01*
X362851Y119014D01*
X360862D01*
X359025Y118252D01*
X357618Y116846D01*
X357523Y116616D01*
X356148D01*
X355846Y117346D01*
X354439Y118752D01*
X352601Y119514D01*
X350612D01*
X348775Y118752D01*
X348270Y118248D01*
X347025Y118496D01*
X346989Y118582D01*
X345582Y119989D01*
X345352Y120084D01*
Y121459D01*
X346082Y121761D01*
X347241Y122920D01*
X348329Y121831D01*
X350167Y121070D01*
X352156D01*
X353993Y121831D01*
X355400Y123238D01*
X355495Y123468D01*
X356870D01*
X357172Y122738D01*
X358579Y121331D01*
X360417Y120570D01*
X362406D01*
X364244Y121331D01*
X365650Y122738D01*
X366411Y124576D01*
Y126565D01*
X365650Y128402D01*
X364244Y129809D01*
X362406Y130570D01*
X360417D01*
X358579Y129809D01*
X357172Y128402D01*
X357077Y128172D01*
X355702D01*
X355400Y128902D01*
X353993Y130309D01*
X352156Y131070D01*
D02*
G37*
G36*
X467243Y166500D02*
X462757D01*
X458326Y165798D01*
X454060Y164412D01*
X450063Y162375D01*
X446433Y159739D01*
X443261Y156566D01*
X440625Y152937D01*
X438588Y148940D01*
X437202Y144674D01*
X436500Y140243D01*
Y135757D01*
X437202Y131326D01*
X438588Y127060D01*
X440625Y123063D01*
X443261Y119433D01*
X446433Y116261D01*
X450063Y113625D01*
X454060Y111588D01*
X458326Y110202D01*
X462757Y109500D01*
X467243D01*
X471674Y110202D01*
X475940Y111588D01*
X479937Y113625D01*
X483567Y116261D01*
X486739Y119433D01*
X489375Y123063D01*
X491412Y127060D01*
X492798Y131326D01*
X493500Y135757D01*
Y140243D01*
X492798Y144674D01*
X491412Y148940D01*
X489375Y152937D01*
X486739Y156566D01*
X483567Y159739D01*
X479937Y162375D01*
X475940Y164412D01*
X471674Y165798D01*
X467243Y166500D01*
D02*
G37*
G36*
X92000Y124250D02*
X90011D01*
X88173Y123489D01*
X86767Y122082D01*
X86005Y120245D01*
Y118255D01*
X86767Y116418D01*
X88173Y115011D01*
X89254Y114563D01*
Y113189D01*
X88168Y112739D01*
X86761Y111332D01*
X86000Y109495D01*
Y107505D01*
X86761Y105668D01*
X88168Y104261D01*
X90005Y103500D01*
X91995D01*
X93832Y104261D01*
X95239Y105668D01*
X96000Y107505D01*
Y109495D01*
X95239Y111332D01*
X93832Y112739D01*
X92751Y113187D01*
Y114561D01*
X93838Y115011D01*
X95244Y116418D01*
X96005Y118255D01*
Y120245D01*
X95244Y122082D01*
X93838Y123489D01*
X92000Y124250D01*
D02*
G37*
G36*
X56084Y111500D02*
X54095D01*
X52257Y110739D01*
X50851Y109332D01*
X50090Y107495D01*
Y105505D01*
X50851Y103668D01*
X52257Y102261D01*
X54095Y101500D01*
X56084D01*
X57922Y102261D01*
X59328Y103668D01*
X60090Y105505D01*
Y107495D01*
X59328Y109332D01*
X57922Y110739D01*
X56084Y111500D01*
D02*
G37*
G36*
X115245Y109000D02*
X113255D01*
X111418Y108239D01*
X110011Y106832D01*
X109250Y104995D01*
Y103005D01*
X110011Y101168D01*
X111418Y99761D01*
X113255Y99000D01*
X115245D01*
X117082Y99761D01*
X118489Y101168D01*
X119250Y103005D01*
Y104995D01*
X118489Y106832D01*
X117082Y108239D01*
X115245Y109000D01*
D02*
G37*
G36*
X73031Y107261D02*
X71041D01*
X69204Y106500D01*
X67797Y105093D01*
X67036Y103256D01*
Y101267D01*
X67797Y99429D01*
X69204Y98022D01*
X71041Y97261D01*
X73031D01*
X74868Y98022D01*
X76275Y99429D01*
X77036Y101267D01*
Y103256D01*
X76275Y105093D01*
X74868Y106500D01*
X73031Y107261D01*
D02*
G37*
G36*
X130495Y111500D02*
X128505D01*
X126668Y110739D01*
X125261Y109332D01*
X124500Y107495D01*
Y105505D01*
X125261Y103668D01*
X126668Y102261D01*
X128030Y101697D01*
X128040Y100327D01*
X126778Y99804D01*
X125371Y98397D01*
X124610Y96560D01*
Y94571D01*
X125371Y92733D01*
X126778Y91326D01*
X128615Y90565D01*
X130605D01*
X132442Y91326D01*
X133849Y92733D01*
X134610Y94571D01*
Y96560D01*
X133849Y98397D01*
X132442Y99804D01*
X131080Y100368D01*
X131070Y101738D01*
X132332Y102261D01*
X133739Y103668D01*
X134500Y105505D01*
Y107495D01*
X133739Y109332D01*
X132332Y110739D01*
X130495Y111500D01*
D02*
G37*
G36*
X56084Y98504D02*
X54095D01*
X52257Y97743D01*
X50851Y96336D01*
X50090Y94499D01*
Y92509D01*
X50851Y90672D01*
X52257Y89265D01*
X54095Y88504D01*
X56084D01*
X57922Y89265D01*
X59328Y90672D01*
X60090Y92509D01*
Y94499D01*
X59328Y96336D01*
X57922Y97743D01*
X56084Y98504D01*
D02*
G37*
G36*
X42910D02*
X40921D01*
X39083Y97743D01*
X37677Y96336D01*
X36916Y94499D01*
Y92509D01*
X37677Y90672D01*
X39083Y89265D01*
X40921Y88504D01*
X42910D01*
X44748Y89265D01*
X46154Y90672D01*
X46916Y92509D01*
Y94499D01*
X46154Y96336D01*
X44748Y97743D01*
X42910Y98504D01*
D02*
G37*
G36*
X28073D02*
X26083D01*
X24246Y97743D01*
X22839Y96336D01*
X22078Y94499D01*
Y92509D01*
X22839Y90672D01*
X24246Y89265D01*
X26083Y88504D01*
X28073D01*
X29910Y89265D01*
X31317Y90672D01*
X32078Y92509D01*
Y94499D01*
X31317Y96336D01*
X29910Y97743D01*
X28073Y98504D01*
D02*
G37*
G36*
X193900Y74250D02*
X191911D01*
X190073Y73489D01*
X188666Y72082D01*
X188616Y71960D01*
X187259Y72003D01*
X185971Y73291D01*
X184133Y74052D01*
X182144D01*
X180306Y73291D01*
X178900Y71885D01*
X178138Y70047D01*
Y68999D01*
X176868Y68473D01*
X176082Y69259D01*
X174245Y70020D01*
X172255D01*
X170418Y69259D01*
X169011Y67853D01*
X168250Y66015D01*
Y64026D01*
X169011Y62188D01*
X170418Y60782D01*
X172255Y60020D01*
X174245D01*
X176082Y60782D01*
X177489Y62188D01*
X178250Y64026D01*
Y65074D01*
X179520Y65600D01*
X180306Y64814D01*
X182144Y64052D01*
X184133D01*
X185971Y64814D01*
X187377Y66220D01*
X187428Y66342D01*
X188785Y66300D01*
X190073Y65011D01*
X191911Y64250D01*
X193900D01*
X195738Y65011D01*
X197144Y66418D01*
X197905Y68255D01*
Y70245D01*
X197144Y72082D01*
X195738Y73489D01*
X193900Y74250D01*
D02*
G37*
G36*
X162745Y69750D02*
X160755D01*
X158918Y68989D01*
X157511Y67582D01*
X156750Y65745D01*
Y63755D01*
X157511Y61918D01*
X158918Y60511D01*
X160755Y59750D01*
X162745D01*
X164582Y60511D01*
X165989Y61918D01*
X166750Y63755D01*
Y65745D01*
X165989Y67582D01*
X164582Y68989D01*
X162745Y69750D01*
D02*
G37*
G36*
X150495Y68250D02*
X148505D01*
X146668Y67489D01*
X145261Y66082D01*
X144500Y64245D01*
Y62255D01*
X145261Y60418D01*
X146668Y59011D01*
X148505Y58250D01*
X150495D01*
X152332Y59011D01*
X153739Y60418D01*
X154500Y62255D01*
Y64245D01*
X153739Y66082D01*
X152332Y67489D01*
X150495Y68250D01*
D02*
G37*
G36*
X97019Y91500D02*
X92981D01*
X89020Y90712D01*
X85289Y89167D01*
X81932Y86923D01*
X79077Y84068D01*
X76833Y80710D01*
X75288Y76980D01*
X74500Y73019D01*
Y68981D01*
X75288Y65020D01*
X76833Y61290D01*
X79077Y57932D01*
X81932Y55077D01*
X85289Y52833D01*
X89020Y51288D01*
X92981Y50500D01*
X97019D01*
X100980Y51288D01*
X104710Y52833D01*
X108068Y55077D01*
X110923Y57932D01*
X113167Y61290D01*
X114712Y65020D01*
X115500Y68981D01*
Y73019D01*
X114712Y76980D01*
X113167Y80710D01*
X110923Y84068D01*
X108068Y86923D01*
X104710Y89167D01*
X100980Y90712D01*
X97019Y91500D01*
D02*
G37*
G36*
X458639Y63450D02*
X455361D01*
X452195Y62602D01*
X449356Y60963D01*
X447038Y58644D01*
X445398Y55806D01*
X444550Y52639D01*
Y49361D01*
X445398Y46195D01*
X447038Y43355D01*
X449356Y41038D01*
X452195Y39398D01*
X455361Y38550D01*
X458639D01*
X461805Y39398D01*
X464645Y41038D01*
X466963Y43355D01*
X468602Y46195D01*
X469450Y49361D01*
Y52639D01*
X468602Y55806D01*
X466963Y58644D01*
X464645Y60963D01*
X461805Y62602D01*
X458639Y63450D01*
D02*
G37*
G36*
X52639D02*
X49361D01*
X46195Y62602D01*
X43355Y60963D01*
X41038Y58644D01*
X39398Y55806D01*
X38550Y52639D01*
Y49361D01*
X39398Y46195D01*
X41038Y43355D01*
X43355Y41038D01*
X46195Y39398D01*
X49361Y38550D01*
X52639D01*
X55806Y39398D01*
X58644Y41038D01*
X60963Y43355D01*
X62602Y46195D01*
X63450Y49361D01*
Y52639D01*
X62602Y55806D01*
X60963Y58644D01*
X58644Y60963D01*
X55806Y62602D01*
X52639Y63450D01*
D02*
G37*
G36*
X308495Y131250D02*
X306505D01*
X304668Y130489D01*
X303261Y129082D01*
X302500Y127245D01*
Y125255D01*
X303261Y123418D01*
X304668Y122011D01*
X304898Y121916D01*
Y120541D01*
X304168Y120239D01*
X302761Y118832D01*
X302000Y116995D01*
Y115005D01*
X302761Y113168D01*
X304168Y111761D01*
X305054Y111394D01*
Y110019D01*
X303988Y109578D01*
X302581Y108171D01*
X301820Y106333D01*
Y104344D01*
X302581Y102507D01*
X303988Y101100D01*
X304218Y101005D01*
Y99630D01*
X303488Y99328D01*
X302081Y97921D01*
X301320Y96083D01*
Y94094D01*
X302081Y92256D01*
X303488Y90850D01*
X304967Y90237D01*
X305094Y88919D01*
X305093Y88915D01*
X304668Y88739D01*
X303261Y87332D01*
X302500Y85494D01*
Y83505D01*
X303261Y81668D01*
X304668Y80261D01*
X304898Y80166D01*
Y78791D01*
X304168Y78489D01*
X302761Y77082D01*
X302000Y75245D01*
Y73255D01*
X302761Y71418D01*
X304168Y70011D01*
X305054Y69644D01*
Y68269D01*
X303988Y67828D01*
X302581Y66421D01*
X301820Y64583D01*
Y62594D01*
X302581Y60757D01*
X303988Y59350D01*
X304218Y59255D01*
Y57880D01*
X303488Y57578D01*
X302081Y56171D01*
X301320Y54333D01*
Y52344D01*
X302081Y50507D01*
X303488Y49100D01*
X303294Y47806D01*
X303000Y47095D01*
Y45106D01*
X303761Y43268D01*
X305168Y41862D01*
X305398Y41766D01*
Y40392D01*
X304668Y40089D01*
X303261Y38682D01*
X302500Y36845D01*
Y34856D01*
X303261Y33018D01*
X304668Y31611D01*
X306505Y30850D01*
X308495D01*
X310332Y31611D01*
X311739Y33018D01*
X312500Y34856D01*
Y36845D01*
X311739Y38682D01*
X310332Y40089D01*
X310102Y40184D01*
Y41559D01*
X310832Y41862D01*
X312239Y43268D01*
X313000Y45106D01*
Y47095D01*
X312239Y48932D01*
X310832Y50339D01*
X310571Y50447D01*
X310559Y50507D01*
X311320Y52344D01*
Y54333D01*
X310559Y56171D01*
X309152Y57578D01*
X308922Y57673D01*
Y59048D01*
X309652Y59350D01*
X311059Y60757D01*
X311820Y62594D01*
Y64583D01*
X311059Y66421D01*
X309652Y67828D01*
X308766Y68195D01*
Y69570D01*
X309832Y70011D01*
X311239Y71418D01*
X312000Y73255D01*
Y75245D01*
X311239Y77082D01*
X309832Y78489D01*
X309602Y78584D01*
Y79959D01*
X310332Y80261D01*
X311739Y81668D01*
X312500Y83505D01*
Y85494D01*
X311739Y87332D01*
X310332Y88739D01*
X308853Y89351D01*
X308726Y90670D01*
X308727Y90674D01*
X309152Y90850D01*
X310559Y92256D01*
X311320Y94094D01*
Y96083D01*
X310559Y97921D01*
X309152Y99328D01*
X308922Y99423D01*
Y100798D01*
X309652Y101100D01*
X311059Y102507D01*
X311820Y104344D01*
Y106333D01*
X311059Y108171D01*
X309652Y109578D01*
X308766Y109945D01*
Y111320D01*
X309832Y111761D01*
X311239Y113168D01*
X312000Y115005D01*
Y116995D01*
X311239Y118832D01*
X309832Y120239D01*
X309602Y120334D01*
Y121709D01*
X310332Y122011D01*
X311739Y123418D01*
X312500Y125255D01*
Y127245D01*
X311739Y129082D01*
X310332Y130489D01*
X308495Y131250D01*
D02*
G37*
G36*
X321245Y131000D02*
X319255D01*
X317418Y130239D01*
X316011Y128832D01*
X315250Y126995D01*
Y125005D01*
X316011Y123168D01*
X317418Y121761D01*
X317648Y121666D01*
Y120291D01*
X316918Y119989D01*
X315511Y118582D01*
X314750Y116745D01*
Y114755D01*
X315511Y112918D01*
X316918Y111511D01*
X317804Y111144D01*
Y109769D01*
X316738Y109328D01*
X315331Y107921D01*
X314570Y106083D01*
Y104094D01*
X315331Y102256D01*
X316738Y100850D01*
X316968Y100755D01*
Y99380D01*
X316238Y99078D01*
X314831Y97671D01*
X314070Y95833D01*
Y93844D01*
X314831Y92007D01*
X316238Y90600D01*
X317717Y89987D01*
X317844Y88669D01*
X317843Y88665D01*
X317418Y88489D01*
X316011Y87082D01*
X315250Y85245D01*
Y83255D01*
X316011Y81418D01*
X317418Y80011D01*
X317648Y79916D01*
Y78541D01*
X316918Y78239D01*
X315511Y76832D01*
X314750Y74995D01*
Y73005D01*
X315511Y71168D01*
X316918Y69761D01*
X317804Y69394D01*
Y68019D01*
X316738Y67578D01*
X315331Y66171D01*
X314570Y64333D01*
Y62344D01*
X315331Y60507D01*
X316738Y59100D01*
X316968Y59005D01*
Y57630D01*
X316238Y57328D01*
X314831Y55921D01*
X314070Y54083D01*
Y52094D01*
X314831Y50257D01*
X316238Y48850D01*
X316044Y47555D01*
X315750Y46845D01*
Y44856D01*
X316511Y43018D01*
X317918Y41611D01*
X318148Y41516D01*
Y40142D01*
X317418Y39839D01*
X316011Y38433D01*
X315250Y36595D01*
Y34606D01*
X316011Y32768D01*
X317418Y31361D01*
X319255Y30600D01*
X321245D01*
X323082Y31361D01*
X324489Y32768D01*
X325250Y34606D01*
Y36595D01*
X324489Y38433D01*
X323082Y39839D01*
X322852Y39934D01*
Y41309D01*
X323582Y41611D01*
X324989Y43018D01*
X325750Y44856D01*
Y46845D01*
X324989Y48683D01*
X323582Y50089D01*
X323776Y51384D01*
X324070Y52094D01*
Y54083D01*
X323309Y55921D01*
X321902Y57328D01*
X321672Y57423D01*
Y58798D01*
X322402Y59100D01*
X323809Y60507D01*
X324570Y62344D01*
Y64333D01*
X323809Y66171D01*
X322402Y67578D01*
X321516Y67945D01*
Y69320D01*
X322582Y69761D01*
X323989Y71168D01*
X324750Y73005D01*
Y74995D01*
X323989Y76832D01*
X322582Y78239D01*
X322352Y78334D01*
Y79709D01*
X323082Y80011D01*
X324489Y81418D01*
X325250Y83255D01*
Y85245D01*
X324489Y87082D01*
X323082Y88489D01*
X321603Y89101D01*
X321476Y90420D01*
X321477Y90424D01*
X321902Y90600D01*
X323309Y92007D01*
X324070Y93844D01*
Y95833D01*
X323309Y97671D01*
X321902Y99078D01*
X321672Y99173D01*
Y100548D01*
X322402Y100850D01*
X323809Y102256D01*
X324570Y104094D01*
Y106083D01*
X323809Y107921D01*
X322402Y109328D01*
X321516Y109695D01*
Y111069D01*
X322582Y111511D01*
X323989Y112918D01*
X324750Y114755D01*
Y116745D01*
X323989Y118582D01*
X322582Y119989D01*
X322352Y120084D01*
Y121459D01*
X323082Y121761D01*
X324489Y123168D01*
X325250Y125005D01*
Y126995D01*
X324489Y128832D01*
X323082Y130239D01*
X321245Y131000D01*
D02*
G37*
G36*
X332688Y130554D02*
X330699D01*
X328861Y129793D01*
X327455Y128387D01*
X326693Y126549D01*
Y124560D01*
X327455Y122722D01*
X328861Y121316D01*
X329091Y121220D01*
Y119846D01*
X328361Y119543D01*
X326955Y118137D01*
X326194Y116299D01*
Y114310D01*
X326955Y112472D01*
X328361Y111066D01*
X329248Y110698D01*
Y109324D01*
X328181Y108882D01*
X326775Y107476D01*
X326013Y105638D01*
Y103649D01*
X326775Y101811D01*
X328181Y100404D01*
X328411Y100309D01*
Y98934D01*
X327681Y98632D01*
X326275Y97226D01*
X325513Y95388D01*
Y93399D01*
X326275Y91561D01*
X327681Y90154D01*
X329160Y89542D01*
X329287Y88223D01*
X329287Y88219D01*
X328861Y88043D01*
X327455Y86637D01*
X326693Y84799D01*
Y82810D01*
X327455Y80972D01*
X328861Y79566D01*
X329091Y79470D01*
Y78096D01*
X328361Y77793D01*
X326955Y76387D01*
X326194Y74549D01*
Y72560D01*
X326955Y70722D01*
X328361Y69316D01*
X329248Y68948D01*
Y67574D01*
X328181Y67132D01*
X326775Y65725D01*
X326013Y63888D01*
Y61899D01*
X326775Y60061D01*
X328181Y58654D01*
X328411Y58559D01*
Y57184D01*
X327681Y56882D01*
X326275Y55476D01*
X325513Y53638D01*
Y51649D01*
X326275Y49811D01*
X327681Y48404D01*
X327488Y47110D01*
X327193Y46399D01*
Y44410D01*
X327955Y42572D01*
X329361Y41166D01*
X329591Y41070D01*
Y39696D01*
X328861Y39393D01*
X327455Y37987D01*
X326693Y36149D01*
Y34160D01*
X327455Y32322D01*
X328861Y30916D01*
X330699Y30155D01*
X332688D01*
X334526Y30916D01*
X335932Y32322D01*
X336693Y34160D01*
Y36149D01*
X335932Y37987D01*
X334526Y39393D01*
X334296Y39489D01*
Y40863D01*
X335026Y41166D01*
X336432Y42572D01*
X337193Y44410D01*
Y46399D01*
X336432Y48237D01*
X335026Y49643D01*
X335219Y50938D01*
X335513Y51649D01*
Y53638D01*
X334752Y55476D01*
X333346Y56882D01*
X333116Y56977D01*
Y58352D01*
X333846Y58654D01*
X335252Y60061D01*
X336013Y61899D01*
Y63888D01*
X335252Y65725D01*
X333846Y67132D01*
X332959Y67499D01*
Y68874D01*
X334026Y69316D01*
X335432Y70722D01*
X336194Y72560D01*
Y74549D01*
X335432Y76387D01*
X334026Y77793D01*
X333796Y77888D01*
Y79263D01*
X334526Y79566D01*
X335932Y80972D01*
X336693Y82810D01*
Y84799D01*
X335932Y86637D01*
X334526Y88043D01*
X333047Y88656D01*
X332920Y89974D01*
X332920Y89978D01*
X333346Y90154D01*
X334752Y91561D01*
X335513Y93399D01*
Y95388D01*
X334752Y97226D01*
X333346Y98632D01*
X333116Y98727D01*
Y100102D01*
X333846Y100404D01*
X335252Y101811D01*
X336013Y103649D01*
Y105638D01*
X335252Y107476D01*
X333846Y108882D01*
X332959Y109249D01*
Y110624D01*
X334026Y111066D01*
X335432Y112472D01*
X336194Y114310D01*
Y116299D01*
X335432Y118137D01*
X334026Y119543D01*
X333796Y119639D01*
Y121013D01*
X334526Y121316D01*
X335932Y122722D01*
X336693Y124560D01*
Y126549D01*
X335932Y128387D01*
X334526Y129793D01*
X332688Y130554D01*
D02*
G37*
G36*
X408019Y61500D02*
X403981D01*
X400020Y60712D01*
X396290Y59167D01*
X392932Y56923D01*
X390077Y54068D01*
X387833Y50710D01*
X386288Y46980D01*
X385500Y43019D01*
Y38981D01*
X386288Y35020D01*
X387833Y31290D01*
X390077Y27932D01*
X392932Y25077D01*
X396290Y22833D01*
X400020Y21288D01*
X403981Y20500D01*
X408019D01*
X411980Y21288D01*
X415710Y22833D01*
X419068Y25077D01*
X421923Y27932D01*
X424167Y31290D01*
X425712Y35020D01*
X426500Y38981D01*
Y43019D01*
X425712Y46980D01*
X424167Y50710D01*
X421923Y54068D01*
X419068Y56923D01*
X415710Y59167D01*
X411980Y60712D01*
X408019Y61500D01*
D02*
G37*
%LPD*%
D76*
X34250Y179000D02*
D03*
D77*
X59650D02*
D03*
D78*
X192000Y484000D02*
D03*
X51000Y457000D02*
D03*
X457000Y51000D02*
D03*
Y457000D02*
D03*
X132000Y484000D02*
D03*
X102000D02*
D03*
X72000D02*
D03*
X457000Y254000D02*
D03*
X51000Y51000D02*
D03*
X162000Y484000D02*
D03*
D79*
X465000Y138000D02*
D03*
Y349000D02*
D03*
D80*
X315000Y203311D02*
D03*
X241500Y478750D02*
D03*
X220968Y339000D02*
D03*
X349911Y39320D02*
D03*
X350161Y52070D02*
D03*
X350607Y63513D02*
D03*
X350161Y75070D02*
D03*
X360411Y74570D02*
D03*
X360857Y63014D02*
D03*
X360411Y51570D02*
D03*
X360161Y38820D02*
D03*
X350911Y90320D02*
D03*
X351161Y103070D02*
D03*
X351607Y114514D02*
D03*
X351161Y126070D02*
D03*
X361411Y125570D02*
D03*
X361857Y114014D02*
D03*
X361411Y102570D02*
D03*
X361161Y89820D02*
D03*
X308000Y46100D02*
D03*
X320750Y45850D02*
D03*
X332193Y45405D02*
D03*
X343750Y45850D02*
D03*
X343250Y35600D02*
D03*
X331693Y35155D02*
D03*
X320250Y35600D02*
D03*
X307500Y35850D02*
D03*
Y84500D02*
D03*
X320250Y84250D02*
D03*
X331693Y83804D02*
D03*
X343250Y84250D02*
D03*
X342750Y74000D02*
D03*
X331194Y73554D02*
D03*
X319750Y74000D02*
D03*
X307000Y74250D02*
D03*
X306320Y53339D02*
D03*
X319070Y53089D02*
D03*
X330513Y52643D02*
D03*
X342070Y53089D02*
D03*
X342570Y63339D02*
D03*
X331013Y62893D02*
D03*
X319570Y63339D02*
D03*
X306820Y63589D02*
D03*
Y105339D02*
D03*
X319570Y105089D02*
D03*
X331013Y104643D02*
D03*
X342570Y105089D02*
D03*
X342070Y94839D02*
D03*
X330513Y94393D02*
D03*
X319070Y94839D02*
D03*
X306320Y95089D02*
D03*
X307000Y116000D02*
D03*
X319750Y115750D02*
D03*
X331194Y115304D02*
D03*
X342750Y115750D02*
D03*
X343250Y126000D02*
D03*
X331693Y125554D02*
D03*
X320250Y126000D02*
D03*
X307500Y126250D02*
D03*
X192905Y69250D02*
D03*
X183138Y69052D02*
D03*
X173250Y65020D02*
D03*
X161750Y64750D02*
D03*
X149500Y63250D02*
D03*
X234398Y422690D02*
D03*
X223373Y415288D02*
D03*
X298715Y489190D02*
D03*
X351500Y488750D02*
D03*
X445113Y472750D02*
D03*
X475000Y447750D02*
D03*
X331500Y400274D02*
D03*
X327000Y392924D02*
D03*
X342703Y406495D02*
D03*
X206542Y332843D02*
D03*
X193292Y330805D02*
D03*
X145000Y264000D02*
D03*
X156752Y276869D02*
D03*
X83952Y262552D02*
D03*
X17462Y347587D02*
D03*
X363500Y449682D02*
D03*
X241197Y308750D02*
D03*
X285250Y446030D02*
D03*
X372500Y440000D02*
D03*
X440352Y374949D02*
D03*
X294500Y454750D02*
D03*
X270921Y437500D02*
D03*
X267761Y319250D02*
D03*
X172000Y147750D02*
D03*
X158750Y132850D02*
D03*
X52118Y197290D02*
D03*
X65473Y198873D02*
D03*
X65619Y215500D02*
D03*
X66659Y224000D02*
D03*
X87000Y475250D02*
D03*
X117080Y493963D02*
D03*
X177000Y492750D02*
D03*
X209500Y489750D02*
D03*
X444999Y421418D02*
D03*
X69000Y463250D02*
D03*
X289250Y269500D02*
D03*
X343677Y360775D02*
D03*
X391028Y361264D02*
D03*
X354750Y339500D02*
D03*
X363284Y389088D02*
D03*
X259492Y353693D02*
D03*
X274414Y352344D02*
D03*
X334750Y326000D02*
D03*
X297250Y385500D02*
D03*
X228424Y209744D02*
D03*
X224129Y188721D02*
D03*
X243500Y244381D02*
D03*
X212000Y174955D02*
D03*
X159750Y177787D02*
D03*
X171400Y173000D02*
D03*
X258939Y182705D02*
D03*
X243939Y182955D02*
D03*
X270189Y187644D02*
D03*
X258939Y209744D02*
D03*
X243939D02*
D03*
X279206Y190705D02*
D03*
X315250Y392363D02*
D03*
X345269Y393919D02*
D03*
X169161Y102103D02*
D03*
X183138D02*
D03*
X172498Y113250D02*
D03*
X95610Y353378D02*
D03*
X184407Y173689D02*
D03*
X146750Y230310D02*
D03*
X350250Y211521D02*
D03*
X344750Y243000D02*
D03*
X332000D02*
D03*
X243500Y257561D02*
D03*
X293674Y244381D02*
D03*
X206956Y397805D02*
D03*
X207706Y432800D02*
D03*
X175750D02*
D03*
X51500Y390689D02*
D03*
X103750Y358378D02*
D03*
X142000Y359750D02*
D03*
X109250Y377668D02*
D03*
X139750Y463508D02*
D03*
X17785Y397960D02*
D03*
X17500Y388019D02*
D03*
Y377710D02*
D03*
Y367710D02*
D03*
Y357460D02*
D03*
X8744Y354901D02*
D03*
X244245Y292311D02*
D03*
X393250Y242500D02*
D03*
X272892Y294750D02*
D03*
X55967Y354628D02*
D03*
X27078Y93504D02*
D03*
X129610Y95565D02*
D03*
X55090Y93504D02*
D03*
X91000Y108500D02*
D03*
X391579Y185091D02*
D03*
X403000Y173750D02*
D03*
Y263500D02*
D03*
X414482Y274431D02*
D03*
X273500Y244381D02*
D03*
X258000D02*
D03*
Y292250D02*
D03*
X363962Y297432D02*
D03*
X232250Y291385D02*
D03*
X264500Y375775D02*
D03*
X375750Y322588D02*
D03*
X145319Y249000D02*
D03*
X160000Y186500D02*
D03*
X84365Y251500D02*
D03*
X22702Y246500D02*
D03*
X52108Y254060D02*
D03*
X102727Y162527D02*
D03*
X66500D02*
D03*
X77704D02*
D03*
X115250D02*
D03*
X142000Y178086D02*
D03*
X130429Y181250D02*
D03*
X114250Y104000D02*
D03*
X72036Y102261D02*
D03*
X41916Y93504D02*
D03*
X55090Y106500D02*
D03*
X91005Y119250D02*
D03*
X129500Y106500D02*
D03*
X403000Y185091D02*
D03*
X403000Y274431D02*
D03*
M02*
